# T6G (Grand Teton) — schematic netlist excerpt (pin names and nets, part order shuffled) for the footprints in the layout excerpt that follows; sources: Cadence DE-HDL packaged netlist, KiCad conversion of 04192023_DAF0TMB3IC0_F0TG_MB_C_brd_V02_OCP.brd

PC358  Q_CAP  3300PF 50V 10% X7R  pkg 0402  page 217 : A = VSENSE_PVDDCR_CPU1_P1_VSEN0 ; B = VSENSE_VSS_SENSE_C_P1
R3711  Q_RES  33.2 1% CHIP  pkg 0402LF  page 252 : A = SMB_VR_SENSOR_3V3AUX_SCL ; B = SMB_VR_SENSOR_3V3AUX_SCL_R
C1793  Q_CAP_DIFFBUS  DIFF BUS_0.22UF 6.3V 20% X6S  pkg C0201  page 65 : \1\ = P5E_CPU0_G3_TX_C_DP<9> ; \2\ = P5E_CPU0_G3_TX_DP<9>

(kicad_pcb
	(version 20260206)
	(generator "pcbnew")
	(generator_version "10.0")
	(general
		(thickness 1.6)
		(legacy_teardrops no)
	)
	(paper "A4")
	(title_block
		(title "04192023_DAF0TMB3IC0_F0TG_MB_C_brd_V02_OCP.brd")
		(comment 1 "Grand Teton / footprints 2970-2972 of 8354")
	)
	(layers
		(0 "F.Cu" signal "TOP")
		(4 "In1.Cu" signal "GND")
		(6 "In2.Cu" signal "IN1")
		(8 "In3.Cu" signal "GND1")
		(10 "In4.Cu" signal "IN2")
		(12 "In5.Cu" signal "GND2")
		(14 "In6.Cu" signal "IN3")
		(16 "In7.Cu" signal "GND3")
		(18 "In8.Cu" signal "VCC")
		(20 "In9.Cu" signal "VCC1")
		(22 "In10.Cu" signal "GND4")
		(24 "In11.Cu" signal "IN4")
		(26 "In12.Cu" signal "GND5")
		(28 "In13.Cu" signal "IN5")
		(30 "In14.Cu" signal "GND6")
		(32 "In15.Cu" signal "IN6")
		(34 "In16.Cu" signal "GND7")
		(2 "B.Cu" signal "BOTTOM")
		(9 "F.Adhes" user "F.Adhesive")
		(11 "B.Adhes" user "B.Adhesive")
		(13 "F.Paste" user "Package Geometry/Pastemask Top")
		(15 "B.Paste" user "Package Geometry/Pastemask Bottom")
		(5 "F.SilkS" user "Ref Des/Silkscreen Top")
		(7 "B.SilkS" user "Ref Des/Silkscreen Bottom")
		(1 "F.Mask" user "Board Geometry/Soldermask Top")
		(3 "B.Mask" user "Board Geometry/Soldermask Bottom")
		(17 "Dwgs.User" user "User.Drawings")
		(19 "Cmts.User" user "User.Comments")
		(21 "Eco1.User" user "User.Eco1")
		(23 "Eco2.User" user "User.Eco2")
		(25 "Edge.Cuts" user "Board Geometry/Outline")
		(27 "Margin" user)
		(31 "F.CrtYd" user "Package Geometry/Place Bound Top")
		(29 "B.CrtYd" user "Package Geometry/Place Bound Bottom")
		(35 "F.Fab" user "Ref Des/Assembly Top")
		(33 "B.Fab" user "Ref Des/Assembly Bottom")
	)
	(footprint ""
		(layer "F.Cu")
		(at 27.559 -359.283)
		(property "Reference" "PC358"
			(at 0 0 0)
			(layer "F.SilkS")
			(hide yes)
			(effects
				(font
					(size 1.27 1.27)
				)
			)
		)
		(property "Value" ""
			(at 0 0 0)
			(layer "F.Fab")
			(effects
				(font
					(size 1.27 1.27)
				)
			)
		)
		(duplicate_pad_numbers_are_jumpers no)
		(fp_line
			(start -0.7874 -0.4064)
			(end 0.7874 -0.4064)
			(stroke
				(width 0.1524)
				(type default)
			)
			(layer "F.SilkS")
		)
		(fp_line
			(start -0.7874 0.4064)
			(end -0.7874 -0.4064)
			(stroke
				(width 0.1524)
				(type default)
			)
			(layer "F.SilkS")
		)
		(fp_line
			(start 0.7874 -0.4064)
			(end 0.7874 0.4064)
			(stroke
				(width 0.1524)
				(type default)
			)
			(layer "F.SilkS")
		)
		(fp_line
			(start 0.7874 0.4064)
			(end -0.7874 0.4064)
			(stroke
				(width 0.1524)
				(type default)
			)
			(layer "F.SilkS")
		)
		(fp_line
			(start -0.67945 -0.305054)
			(end -0.12065 -0.305054)
			(stroke
				(width 0.1)
				(type default)
			)
			(layer "F.Fab")
		)
		(fp_line
			(start -0.67945 0.3048)
			(end -0.67945 -0.305054)
			(stroke
				(width 0.1)
				(type default)
			)
			(layer "F.Fab")
		)
		(fp_line
			(start -0.12065 -0.305054)
			(end -0.12065 -0.2794)
			(stroke
				(width 0.1)
				(type default)
			)
			(layer "F.Fab")
		)
		(fp_line
			(start -0.12065 -0.2794)
			(end 0.12065 -0.2794)
			(stroke
				(width 0.1)
				(type default)
			)
			(layer "F.Fab")
		)
		(fp_line
			(start -0.12065 0.2794)
			(end -0.12065 0.3048)
			(stroke
				(width 0.1)
				(type default)
			)
			(layer "F.Fab")
		)
		(fp_line
			(start -0.12065 0.3048)
			(end -0.67945 0.3048)
			(stroke
				(width 0.1)
				(type default)
			)
			(layer "F.Fab")
		)
		(fp_line
			(start 0.120396 0.2794)
			(end -0.12065 0.2794)
			(stroke
				(width 0.1)
				(type default)
			)
			(layer "F.Fab")
		)
		(fp_line
			(start 0.120396 0.3048)
			(end 0.120396 0.2794)
			(stroke
				(width 0.1)
				(type default)
			)
			(layer "F.Fab")
		)
		(fp_line
			(start 0.12065 -0.3048)
			(end 0.67945 -0.3048)
			(stroke
				(width 0.1)
				(type default)
			)
			(layer "F.Fab")
		)
		(fp_line
			(start 0.12065 -0.2794)
			(end 0.12065 -0.3048)
			(stroke
				(width 0.1)
				(type default)
			)
			(layer "F.Fab")
		)
		(fp_line
			(start 0.67945 -0.3048)
			(end 0.67945 0.3048)
			(stroke
				(width 0.1)
				(type default)
			)
			(layer "F.Fab")
		)
		(fp_line
			(start 0.67945 0.3048)
			(end 0.120396 0.3048)
			(stroke
				(width 0.1)
				(type default)
			)
			(layer "F.Fab")
		)
		(pad "1" smd circle
			(at -0.40005 0)
			(size 0 0)
			(layers "F.Cu" "F.Mask" "F.Paste")
			(net "VSENSE_PVDDCR_CPU1_P1_VSEN0")
		)
		(pad "2" smd circle
			(at 0.40005 0)
			(size 0 0)
			(layers "F.Cu" "F.Mask" "F.Paste")
			(net "VSENSE_VSS_SENSE_C_P1")
		)
	)
	(footprint ""
		(layer "F.Cu")
		(at 407.685748 -16.100298 90)
		(property "Reference" "C1793"
			(at 0 0 90)
			(layer "F.SilkS")
			(hide yes)
			(effects
				(font
					(size 1.27 1.27)
				)
			)
		)
		(property "Value" ""
			(at 0 0 90)
			(layer "F.Fab")
			(effects
				(font
					(size 1.27 1.27)
				)
			)
		)
		(duplicate_pad_numbers_are_jumpers no)
		(fp_line
			(start 0.299974 -0.150114)
			(end 0.299974 0.150114)
			(stroke
				(width 0.1)
				(type default)
			)
			(layer "F.Fab")
		)
		(fp_line
			(start -0.299974 -0.150114)
			(end 0.299974 -0.150114)
			(stroke
				(width 0.1)
				(type default)
			)
			(layer "F.Fab")
		)
		(fp_line
			(start 0.299974 0.150114)
			(end -0.299974 0.150114)
			(stroke
				(width 0.1)
				(type default)
			)
			(layer "F.Fab")
		)
		(fp_line
			(start -0.299974 0.150114)
			(end -0.299974 -0.150114)
			(stroke
				(width 0.1)
				(type default)
			)
			(layer "F.Fab")
		)
		(pad "1" smd rect
			(at -0.2667 0 90)
			(size 0.3048 0.381)
			(layers "F.Cu" "F.Mask" "F.Paste")
			(net "P5E_CPU0_G3_TX_C_DP<9>")
		)
		(pad "2" smd rect
			(at 0.2667 0 90)
			(size 0.3048 0.381)
			(layers "F.Cu" "F.Mask" "F.Paste")
			(net "P5E_CPU0_G3_TX_DP<9>")
		)
	)
	(footprint ""
		(layer "F.Cu")
		(at 271.085056 -122.84837 180)
		(property "Reference" "R3711"
			(at 0 0 180)
			(layer "F.SilkS")
			(hide yes)
			(effects
				(font
					(size 1.27 1.27)
				)
			)
		)
		(property "Value" ""
			(at 0 0 180)
			(layer "F.Fab")
			(effects
				(font
					(size 1.27 1.27)
				)
			)
		)
		(duplicate_pad_numbers_are_jumpers no)
		(fp_line
			(start 0.7874 0.4064)
			(end -0.7874 0.4064)
			(stroke
				(width 0.1524)
				(type default)
			)
			(layer "F.SilkS")
		)
		(fp_line
			(start 0.7874 -0.4064)
			(end 0.7874 0.4064)
			(stroke
				(width 0.1524)
				(type default)
			)
			(layer "F.SilkS")
		)
		(fp_line
			(start -0.7874 0.4064)
			(end -0.7874 -0.4064)
			(stroke
				(width 0.1524)
				(type default)
			)
			(layer "F.SilkS")
		)
		(fp_line
			(start -0.7874 -0.4064)
			(end 0.7874 -0.4064)
			(stroke
				(width 0.1524)
				(type default)
			)
			(layer "F.SilkS")
		)
		(fp_line
			(start 0.67945 0.3048)
			(end 0.120396 0.3048)
			(stroke
				(width 0.1)
				(type default)
			)
			(layer "F.Fab")
		)
		(fp_line
			(start 0.67945 -0.3048)
			(end 0.67945 0.3048)
			(stroke
				(width 0.1)
				(type default)
			)
			(layer "F.Fab")
		)
		(fp_line
			(start 0.12065 -0.2794)
			(end 0.12065 -0.3048)
			(stroke
				(width 0.1)
				(type default)
			)
			(layer "F.Fab")
		)
		(fp_line
			(start 0.12065 -0.3048)
			(end 0.67945 -0.3048)
			(stroke
				(width 0.1)
				(type default)
			)
			(layer "F.Fab")
		)
		(fp_line
			(start 0.120396 0.3048)
			(end 0.120396 0.2794)
			(stroke
				(width 0.1)
				(type default)
			)
			(layer "F.Fab")
		)
		(fp_line
			(start 0.120396 0.2794)
			(end -0.12065 0.2794)
			(stroke
				(width 0.1)
				(type default)
			)
			(layer "F.Fab")
		)
		(fp_line
			(start -0.12065 0.3048)
			(end -0.67945 0.3048)
			(stroke
				(width 0.1)
				(type default)
			)
			(layer "F.Fab")
		)
		(fp_line
			(start -0.12065 0.2794)
			(end -0.12065 0.3048)
			(stroke
				(width 0.1)
				(type default)
			)
			(layer "F.Fab")
		)
		(fp_line
			(start -0.12065 -0.2794)
			(end 0.12065 -0.2794)
			(stroke
				(width 0.1)
				(type default)
			)
			(layer "F.Fab")
		)
		(fp_line
			(start -0.12065 -0.305054)
			(end -0.12065 -0.2794)
			(stroke
				(width 0.1)
				(type default)
			)
			(layer "F.Fab")
		)
		(fp_line
			(start -0.67945 0.3048)
			(end -0.67945 -0.305054)
			(stroke
				(width 0.1)
				(type default)
			)
			(layer "F.Fab")
		)
		(fp_line
			(start -0.67945 -0.305054)
			(end -0.12065 -0.305054)
			(stroke
				(width 0.1)
				(type default)
			)
			(layer "F.Fab")
		)
		(pad "1" smd circle
			(at -0.40005 0 180)
			(size 0 0)
			(layers "F.Cu" "F.Mask" "F.Paste")
			(net "SMB_VR_SENSOR_3V3AUX_SCL")
		)
		(pad "2" smd circle
			(at 0.40005 0 180)
			(size 0 0)
			(layers "F.Cu" "F.Mask" "F.Paste")
			(net "SMB_VR_SENSOR_3V3AUX_SCL_R")
		)
	)
)
